FILE_TYPE = MULTI_PHYS_TABLE;
PART 'RCC_DFX1940'
{==============================================================================================================================================================================}
:PACK_TYPE | MATERIAL | PART_NUMBER = EnvComp | PART_NUMBER | JEDEC_TYPE              | CLASS | DESCRIPTION                       | HEIGHT       | COMPONENT_TYPE  | SPEED_URL | Status |RPL| AML | Bus_Unit | Days ;
{==============================================================================================================================================================================}
'ID2'      | 'EMPTY'  | 'N_A'(!)    = '' | 'N_A'       | 'DFX1940ID2_10MIL'      | 'IO'  | 'DFx1940 ID2 0.010/0.010/0.0235'  | '0.00001 IN' | 'PSEUDO' | 'http://speed.intel.com:8081/speed/module/pdm/item/pdm_item_detail_direct.asp?item_cde=N_A&item_rev=01&url_param=unused' | '???' | '???' | '???' | '' | '???' 
'ID4'      | 'EMPTY'  | 'N_A'(!)    = '' | 'N_A'       | 'DFX1940ID4_9MIL'       | 'IO'  | 'DFx1940 ID4 0.010/0.010/0.0215'  | '0.00001 IN' | 'PSEUDO' | 'http://speed.intel.com:8081/speed/module/pdm/item/pdm_item_detail_direct.asp?item_cde=N_A&item_rev=01&url_param=unused' | '???' | '???' | '???' | '' | '???' 
'ID4A'     | 'EMPTY'  | 'N_A'(!)    = '' | 'N_A'       | 'DFX1940ID4_8_5MIL'     | 'IO'  | 'DFx1940 ID4 0.010/0.010/0.0205'  | '0.00001 IN' | 'PSEUDO' | 'http://speed.intel.com:8081/speed/module/pdm/item/pdm_item_detail_direct.asp?item_cde=N_A&item_rev=01&url_param=unused' | '???' | '???' | '???' | '' | '???' 
END_PART
END.
